# SCM (Grand Teton) — schematic netlist excerpt (pin names and nets, part order shuffled) for the footprints in the layout excerpt that follows; sources: Cadence DE-HDL packaged netlist, KiCad conversion of 12092022_DA0F0TMDCD0_F0T_Management_Board_D_brd_V3_OCP.brd

R547  Q_RES  33.2 1% CHIP  pkg 0402LF  page 21 : A = SPI_BMC_CS1_FLASH_R_N ; B = SPI_BMC_BOOT_CS1_R_N
R301  Q_RES  0 5% CHIP  pkg 0402LF  page 41 : A = P3V3_AUX ; B = VCCIO5

(kicad_pcb
	(version 20260206)
	(generator "pcbnew")
	(generator_version "10.0")
	(general
		(thickness 1.6)
		(legacy_teardrops no)
	)
	(paper "A4")
	(title_block
		(title "12092022_DA0F0TMDCD0_F0T_Management_Board_D_brd_V3_OCP.brd")
		(comment 1 "Grand Teton / footprints 1006-1007 of 1440")
	)
	(layers
		(0 "F.Cu" signal "TOP")
		(4 "In1.Cu" signal "GND")
		(6 "In2.Cu" signal "IN1")
		(8 "In3.Cu" signal "GND1")
		(10 "In4.Cu" signal "IN2")
		(12 "In5.Cu" signal "VCC")
		(14 "In6.Cu" signal "VCC1")
		(16 "In7.Cu" signal "IN3")
		(18 "In8.Cu" signal "GND2")
		(20 "In9.Cu" signal "IN4")
		(22 "In10.Cu" signal "GND3")
		(2 "B.Cu" signal "BOTTOM")
		(9 "F.Adhes" user "F.Adhesive")
		(11 "B.Adhes" user "B.Adhesive")
		(13 "F.Paste" user "Package Geometry/Pastemask Top")
		(15 "B.Paste" user "Package Geometry/Pastemask Bottom")
		(5 "F.SilkS" user "Ref Des/Silkscreen Top")
		(7 "B.SilkS" user "Ref Des/Silkscreen Bottom")
		(1 "F.Mask" user "Board Geometry/Soldermask Top")
		(3 "B.Mask" user "Board Geometry/Soldermask Bottom")
		(17 "Dwgs.User" user "User.Drawings")
		(19 "Cmts.User" user "User.Comments")
		(21 "Eco1.User" user "User.Eco1")
		(23 "Eco2.User" user "User.Eco2")
		(25 "Edge.Cuts" user "Board Geometry/Outline")
		(27 "Margin" user)
		(31 "F.CrtYd" user "Package Geometry/Place Bound Top")
		(29 "B.CrtYd" user "Package Geometry/Place Bound Bottom")
		(35 "F.Fab" user "Ref Des/Assembly Top")
		(33 "B.Fab" user "Ref Des/Assembly Bottom")
	)
	(footprint ""
		(layer "B.Cu")
		(at 59.3852 -77.9526)
		(property "Reference" "R547"
			(at 0 0 0)
			(layer "B.SilkS")
			(hide yes)
			(effects
				(font
					(size 1.27 1.27)
				)
				(justify mirror)
			)
		)
		(property "Value" ""
			(at 0 0 0)
			(layer "B.Fab")
			(effects
				(font
					(size 1.27 1.27)
				)
				(justify mirror)
			)
		)
		(duplicate_pad_numbers_are_jumpers no)
		(fp_line
			(start -0.7874 -0.4064)
			(end -0.7874 0.4064)
			(stroke
				(width 0.1524)
				(type default)
			)
			(layer "B.SilkS")
		)
		(fp_line
			(start -0.7874 0.4064)
			(end 0.7874 0.4064)
			(stroke
				(width 0.1524)
				(type default)
			)
			(layer "B.SilkS")
		)
		(fp_line
			(start 0.7874 -0.4064)
			(end -0.7874 -0.4064)
			(stroke
				(width 0.1524)
				(type default)
			)
			(layer "B.SilkS")
		)
		(fp_line
			(start 0.7874 0.4064)
			(end 0.7874 -0.4064)
			(stroke
				(width 0.1524)
				(type default)
			)
			(layer "B.SilkS")
		)
		(fp_line
			(start -0.67945 -0.3048)
			(end -0.67945 0.3048)
			(stroke
				(width 0.1)
				(type default)
			)
			(layer "B.Fab")
		)
		(fp_line
			(start -0.67945 0.3048)
			(end -0.120396 0.3048)
			(stroke
				(width 0.1)
				(type default)
			)
			(layer "B.Fab")
		)
		(fp_line
			(start -0.12065 -0.3048)
			(end -0.67945 -0.3048)
			(stroke
				(width 0.1)
				(type default)
			)
			(layer "B.Fab")
		)
		(fp_line
			(start -0.12065 -0.2794)
			(end -0.12065 -0.3048)
			(stroke
				(width 0.1)
				(type default)
			)
			(layer "B.Fab")
		)
		(fp_line
			(start -0.120396 0.2794)
			(end 0.12065 0.2794)
			(stroke
				(width 0.1)
				(type default)
			)
			(layer "B.Fab")
		)
		(fp_line
			(start -0.120396 0.3048)
			(end -0.120396 0.2794)
			(stroke
				(width 0.1)
				(type default)
			)
			(layer "B.Fab")
		)
		(fp_line
			(start 0.12065 -0.305054)
			(end 0.12065 -0.2794)
			(stroke
				(width 0.1)
				(type default)
			)
			(layer "B.Fab")
		)
		(fp_line
			(start 0.12065 -0.2794)
			(end -0.12065 -0.2794)
			(stroke
				(width 0.1)
				(type default)
			)
			(layer "B.Fab")
		)
		(fp_line
			(start 0.12065 0.2794)
			(end 0.12065 0.3048)
			(stroke
				(width 0.1)
				(type default)
			)
			(layer "B.Fab")
		)
		(fp_line
			(start 0.12065 0.3048)
			(end 0.67945 0.3048)
			(stroke
				(width 0.1)
				(type default)
			)
			(layer "B.Fab")
		)
		(fp_line
			(start 0.67945 -0.305054)
			(end 0.12065 -0.305054)
			(stroke
				(width 0.1)
				(type default)
			)
			(layer "B.Fab")
		)
		(fp_line
			(start 0.67945 0.3048)
			(end 0.67945 -0.305054)
			(stroke
				(width 0.1)
				(type default)
			)
			(layer "B.Fab")
		)
		(pad "1" smd circle
			(at 0.40005 0 180)
			(size 0 0)
			(layers "B.Cu" "B.Mask" "B.Paste")
			(net "SPI_BMC_CS1_FLASH_R_N")
		)
		(pad "2" smd circle
			(at -0.40005 0 180)
			(size 0 0)
			(layers "B.Cu" "B.Mask" "B.Paste")
			(net "SPI_BMC_BOOT_CS1_R_N")
		)
	)
	(footprint ""
		(layer "B.Cu")
		(at 26.416 -92.075 90)
		(property "Reference" "R301"
			(at 0 0 90)
			(layer "B.SilkS")
			(hide yes)
			(effects
				(font
					(size 1.27 1.27)
				)
				(justify mirror)
			)
		)
		(property "Value" ""
			(at 0 0 90)
			(layer "B.Fab")
			(effects
				(font
					(size 1.27 1.27)
				)
				(justify mirror)
			)
		)
		(duplicate_pad_numbers_are_jumpers no)
		(fp_line
			(start 0.7874 -0.4064)
			(end -0.7874 -0.4064)
			(stroke
				(width 0.1524)
				(type default)
			)
			(layer "B.SilkS")
		)
		(fp_line
			(start -0.7874 -0.4064)
			(end -0.7874 0.4064)
			(stroke
				(width 0.1524)
				(type default)
			)
			(layer "B.SilkS")
		)
		(fp_line
			(start 0.7874 0.4064)
			(end 0.7874 -0.4064)
			(stroke
				(width 0.1524)
				(type default)
			)
			(layer "B.SilkS")
		)
		(fp_line
			(start -0.7874 0.4064)
			(end 0.7874 0.4064)
			(stroke
				(width 0.1524)
				(type default)
			)
			(layer "B.SilkS")
		)
		(fp_line
			(start 0.67945 -0.305054)
			(end 0.12065 -0.305054)
			(stroke
				(width 0.1)
				(type default)
			)
			(layer "B.Fab")
		)
		(fp_line
			(start 0.12065 -0.305054)
			(end 0.12065 -0.2794)
			(stroke
				(width 0.1)
				(type default)
			)
			(layer "B.Fab")
		)
		(fp_line
			(start -0.12065 -0.3048)
			(end -0.67945 -0.3048)
			(stroke
				(width 0.1)
				(type default)
			)
			(layer "B.Fab")
		)
		(fp_line
			(start -0.67945 -0.3048)
			(end -0.67945 0.3048)
			(stroke
				(width 0.1)
				(type default)
			)
			(layer "B.Fab")
		)
		(fp_line
			(start 0.12065 -0.2794)
			(end -0.12065 -0.2794)
			(stroke
				(width 0.1)
				(type default)
			)
			(layer "B.Fab")
		)
		(fp_line
			(start -0.12065 -0.2794)
			(end -0.12065 -0.3048)
			(stroke
				(width 0.1)
				(type default)
			)
			(layer "B.Fab")
		)
		(fp_line
			(start 0.12065 0.2794)
			(end 0.12065 0.3048)
			(stroke
				(width 0.1)
				(type default)
			)
			(layer "B.Fab")
		)
		(fp_line
			(start -0.120396 0.2794)
			(end 0.12065 0.2794)
			(stroke
				(width 0.1)
				(type default)
			)
			(layer "B.Fab")
		)
		(fp_line
			(start 0.67945 0.3048)
			(end 0.67945 -0.305054)
			(stroke
				(width 0.1)
				(type default)
			)
			(layer "B.Fab")
		)
		(fp_line
			(start 0.12065 0.3048)
			(end 0.67945 0.3048)
			(stroke
				(width 0.1)
				(type default)
			)
			(layer "B.Fab")
		)
		(fp_line
			(start -0.120396 0.3048)
			(end -0.120396 0.2794)
			(stroke
				(width 0.1)
				(type default)
			)
			(layer "B.Fab")
		)
		(fp_line
			(start -0.67945 0.3048)
			(end -0.120396 0.3048)
			(stroke
				(width 0.1)
				(type default)
			)
			(layer "B.Fab")
		)
		(pad "1" smd circle
			(at 0.40005 0 270)
			(size 0 0)
			(layers "B.Cu" "B.Mask" "B.Paste")
			(net "P3V3_AUX")
		)
		(pad "2" smd circle
			(at -0.40005 0 270)
			(size 0 0)
			(layers "B.Cu" "B.Mask" "B.Paste")
			(net "VCCIO5")
		)
	)
)
